(kicad_pcb
	(version 20241229)
	(generator "pcbnew")
	(generator_version "9.0")
	(general
		(thickness 1.61)
		(legacy_teardrops no)
	)
	(paper "A3")
	(title_block
		(title "SO-DIMM DDR5 Tester")
		(date "2025-11-26")
		(rev "1.3.0")
		(comment 9 "footprints 153-156 of 627")
	)
	(layers
		(0 "F.Cu" signal)
		(4 "In1.Cu" power)
		(6 "In2.Cu" mixed)
		(8 "In3.Cu" power)
		(10 "In4.Cu" mixed)
		(12 "In5.Cu" power)
		(14 "In6.Cu" mixed)
		(16 "In7.Cu" power)
		(18 "In8.Cu" power)
		(20 "In9.Cu" mixed)
		(22 "In10.Cu" power)
		(2 "B.Cu" signal)
		(9 "F.Adhes" user "F.Adhesive")
		(11 "B.Adhes" user "B.Adhesive")
		(13 "F.Paste" user)
		(15 "B.Paste" user)
		(5 "F.SilkS" user "F.Silkscreen")
		(7 "B.SilkS" user "B.Silkscreen")
		(1 "F.Mask" user)
		(3 "B.Mask" user)
		(17 "Dwgs.User" user "User.Drawings")
		(19 "Cmts.User" user "User.Comments")
		(21 "Eco1.User" user "User.Eco1")
		(23 "Eco2.User" user "User.Eco2")
		(25 "Edge.Cuts" user)
		(27 "Margin" user)
		(31 "F.CrtYd" user "F.Courtyard")
		(29 "B.CrtYd" user "B.Courtyard")
		(35 "F.Fab" user)
		(33 "B.Fab" user)
	)
	(footprint "antmicro-footprints:LGA-33_7x7mm_P0.65mm"
		(layer "F.Cu")
		(at 198.020501 184.3105 -90)
		(property "Reference" "U19"
			(at 4.5895 -1.779499 0)
			(layer "F.SilkS")
			(effects
				(font
					(size 0.7 0.7)
					(thickness 0.15)
				)
				(justify left bottom)
			)
		)
		(property "Value" "MPM54304GMN"
			(at 0 5 270)
			(layer "F.Fab")
			(effects
				(font
					(size 0.7 0.7)
					(thickness 0.15)
				)
				(justify left bottom)
			)
		)
		(property "Datasheet" "https://www.monolithicpower.com/en/documentview/productdocument/index/version/2/document_type/Datasheet/lang/en/sku/MPM54304/document_id/4982/"
			(at 0 0 270)
			(layer "F.Fab")
			(hide yes)
			(effects
				(font
					(size 1.27 1.27)
					(thickness 0.15)
				)
			)
		)
		(property "Author" "Antmicro"
			(at 13.710001 382.331001 0)
			(layer "F.Fab")
			(hide yes)
			(effects
				(font
					(size 1 1)
					(thickness 0.15)
				)
			)
		)
		(property "License" "Apache-2.0"
			(at 13.710001 382.331001 0)
			(layer "F.Fab")
			(hide yes)
			(effects
				(font
					(size 1 1)
					(thickness 0.15)
				)
			)
		)
		(property "MPN" "MPM54304GMN-0000"
			(at 13.710001 382.331001 0)
			(layer "F.Fab")
			(hide yes)
			(effects
				(font
					(size 1 1)
					(thickness 0.15)
				)
			)
		)
		(property "Manufacturer" "Monolithic Power Systems"
			(at 13.710001 382.331001 0)
			(layer "F.Fab")
			(hide yes)
			(effects
				(font
					(size 1 1)
					(thickness 0.15)
				)
			)
		)
		(property ki_fp_filters "CP_48_13_ADI CP_48_13_ADI-M CP_48_13_ADI-L")
		(sheetname "/Supply/")
		(sheetfile "supply.kicad_sch")
		(solder_paste_margin_ratio -0.1)
		(attr smd)
		(fp_line
			(start -3.65 3.648)
			(end -3.65 2.922)
			(stroke
				(width 0.15)
				(type solid)
			)
			(layer "F.SilkS")
		)
		(fp_line
			(start -2.926 3.648)
			(end -3.65 3.648)
			(stroke
				(width 0.15)
				(type solid)
			)
			(layer "F.SilkS")
		)
		(fp_line
			(start 2.922 3.648)
			(end 3.648 3.648)
			(stroke
				(width 0.15)
				(type solid)
			)
			(layer "F.SilkS")
		)
		(fp_line
			(start 3.648 3.648)
			(end 3.648 2.922)
			(stroke
				(width 0.15)
				(type solid)
			)
			(layer "F.SilkS")
		)
		(fp_line
			(start -3.665 -2.928)
			(end -3.665 -3.653)
			(stroke
				(width 0.15)
				(type solid)
			)
			(layer "F.SilkS")
		)
		(fp_line
			(start 2.922 -3.65)
			(end 3.648 -3.65)
			(stroke
				(width 0.15)
				(type solid)
			)
			(layer "F.SilkS")
		)
		(fp_line
			(start 3.648 -3.65)
			(end 3.648 -2.926)
			(stroke
				(width 0.15)
				(type solid)
			)
			(layer "F.SilkS")
		)
		(fp_line
			(start -3.665 -3.653)
			(end -2.94 -3.653)
			(stroke
				(width 0.15)
				(type solid)
			)
			(layer "F.SilkS")
		)
		(fp_circle
			(center -3.8 -1.925)
			(end -3.75 -1.925)
			(stroke
				(width 0.15)
				(type solid)
			)
			(fill yes)
			(layer "F.SilkS")
		)
		(fp_rect
			(start -4 -4)
			(end 3.999 3.999)
			(stroke
				(width 0.05)
				(type solid)
			)
			(fill no)
			(layer "F.CrtYd")
		)
		(fp_line
			(start -3.5 3.499)
			(end 3.499 3.499)
			(stroke
				(width 0.15)
				(type solid)
			)
			(layer "F.Fab")
		)
		(fp_line
			(start 3.499 3.499)
			(end 3.499 -3.5)
			(stroke
				(width 0.15)
				(type solid)
			)
			(layer "F.Fab")
		)
		(fp_line
			(start -3.5 -3.5)
			(end -3.5 3.499)
			(stroke
				(width 0.15)
				(type solid)
			)
			(layer "F.Fab")
		)
		(fp_line
			(start -3.101 -3.5)
			(end -3.5 -3.101)
			(stroke
				(width 0.15)
				(type solid)
			)
			(layer "F.Fab")
		)
		(fp_line
			(start 3.499 -3.5)
			(end -3.5 -3.5)
			(stroke
				(width 0.15)
				(type solid)
			)
			(layer "F.Fab")
		)
		(pad "1" smd rect
			(at -3.138 -1.625)
			(size 0.3 1.125)
			(layers "F.Cu" "F.Mask" "F.Paste")
			(net 35 "/Supply/spare_local")
			(pinfunction "VOUT3")
			(pintype "power_out")
		)
		(pad "2" smd rect
			(at -3.138 -0.975)
			(size 0.3 1.125)
			(layers "F.Cu" "F.Mask" "F.Paste")
			(net 1 "GND")
			(pinfunction "GND")
			(pintype "passive")
		)
		(pad "3" smd rect
			(at -3.138 -0.328)
			(size 0.3 1.125)
			(layers "F.Cu" "F.Mask" "F.Paste")
			(net 690 "/I^{2}C/PWR.SDA")
			(pinfunction "SDA")
			(pintype "bidirectional")
		)
		(pad "4" smd rect
			(at -3.138 0.325)
			(size 0.3 1.125)
			(layers "F.Cu" "F.Mask" "F.Paste")
			(net 691 "/I^{2}C/PWR.SCL")
			(pinfunction "SCL")
			(pintype "input")
		)
		(pad "5" smd rect
			(at -3.138 0.972)
			(size 0.3 1.125)
			(layers "F.Cu" "F.Mask" "F.Paste")
			(net 1 "GND")
			(pinfunction "GND")
			(pintype "passive")
		)
		(pad "6" smd rect
			(at -3.138 1.624)
			(size 0.3 1.125)
			(layers "F.Cu" "F.Mask" "F.Paste")
			(net 211 "/Supply/FB2")
			(pinfunction "FB2")
			(pintype "input")
		)
		(pad "7" smd rect
			(at -2.926 3.136 90)
			(size 0.3 1.125)
			(layers "F.Cu" "F.Mask" "F.Paste")
			(net 1 "GND")
			(pinfunction "GND")
			(pintype "passive")
		)
		(pad "8" smd rect
			(at -2.275 3.136 90)
			(size 0.3 1.125)
			(layers "F.Cu" "F.Mask" "F.Paste")
			(net 51 "/Supply/1V8_local")
			(pinfunction "VOUT2")
			(pintype "power_out")
		)
		(pad "9" smd rect
			(at -1.625 3.136 270)
			(size 0.3 1.125)
			(layers "F.Cu" "F.Mask" "F.Paste")
			(net 51 "/Supply/1V8_local")
			(pinfunction "VOUT2")
			(pintype "passive")
		)
		(pad "10" smd rect
			(at -0.975 3.136 270)
			(size 0.3 1.125)
			(layers "F.Cu" "F.Mask" "F.Paste")
			(net 1 "GND")
			(pinfunction "GND")
			(pintype "passive")
		)
		(pad "11" smd rect
			(at -0.328 3.136 270)
			(size 0.3 1.125)
			(layers "F.Cu" "F.Mask" "F.Paste")
			(net 726 "unconnected-(U19-SW2-Pad11)")
			(pinfunction "SW2")
			(pintype "power_out+no_connect")
		)
		(pad "12" smd rect
			(at 0.325 3.136 270)
			(size 0.3 1.125)
			(layers "F.Cu" "F.Mask" "F.Paste")
			(net 727 "unconnected-(U19-SW1-Pad12)")
			(pinfunction "SW1")
			(pintype "power_out+no_connect")
		)
		(pad "13" smd rect
			(at 0.972 3.136 270)
			(size 0.3 1.125)
			(layers "F.Cu" "F.Mask" "F.Paste")
			(net 1 "GND")
			(pinfunction "GND")
			(pintype "passive")
		)
		(pad "14" smd rect
			(at 1.624 3.136 270)
			(size 0.3 1.125)
			(layers "F.Cu" "F.Mask" "F.Paste")
			(net 42 "/Supply/MGTAVCC_local")
			(pinfunction "VOUT1")
			(pintype "power_out")
		)
		(pad "15" smd rect
			(at 2.273 3.136 270)
			(size 0.3 1.125)
			(layers "F.Cu" "F.Mask" "F.Paste")
			(net 42 "/Supply/MGTAVCC_local")
			(pinfunction "VOUT1")
			(pintype "passive")
		)
		(pad "16" smd rect
			(at 2.922 3.136 270)
			(size 0.3 1.125)
			(layers "F.Cu" "F.Mask" "F.Paste")
			(net 1 "GND")
			(pinfunction "GND")
			(pintype "passive")
		)
		(pad "17" smd rect
			(at 3.136 1.624)
			(size 0.3 1.125)
			(layers "F.Cu" "F.Mask" "F.Paste")
			(net 1 "GND")
			(pinfunction "SGND1")
			(pintype "power_out")
		)
		(pad "18" smd rect
			(at 3.136 0.972)
			(size 0.3 1.125)
			(layers "F.Cu" "F.Mask" "F.Paste")
			(net 210 "/Supply/FB1")
			(pinfunction "FB1")
			(pintype "input")
		)
		(pad "19" smd rect
			(at 3.136 0.325)
			(size 0.3 1.125)
			(layers "F.Cu" "F.Mask" "F.Paste")
			(net 222 "/Supply/EN2")
			(pinfunction "EN/SYNCI")
			(pintype "input")
		)
		(pad "20" smd rect
			(at 3.136 -0.328)
			(size 0.3 1.125)
			(layers "F.Cu" "F.Mask" "F.Paste")
			(net 1 "GND")
			(pinfunction "GND")
			(pintype "passive")
		)
		(pad "21" smd rect
			(at 3.136 -0.975)
			(size 0.3 1.125)
			(layers "F.Cu" "F.Mask" "F.Paste")
			(net 1 "GND")
			(pinfunction "GND")
			(pintype "passive")
		)
		(pad "22" smd rect
			(at 3.136 -1.625)
			(size 0.3 1.125)
			(layers "F.Cu" "F.Mask" "F.Paste")
			(net 58 "/Supply/1V7_local")
			(pinfunction "VOUT4")
			(pintype "power_out")
		)
		(pad "23" smd rect
			(at 2.922 -3.138 90)
			(size 0.3 1.125)
			(layers "F.Cu" "F.Mask" "F.Paste")
			(net 58 "/Supply/1V7_local")
			(pinfunction "VOUT4")
			(pintype "passive")
		)
		(pad "24" smd rect
			(at 2.273 -3.138 90)
			(size 0.3 1.125)
			(layers "F.Cu" "F.Mask" "F.Paste")
			(net 220 "/Supply/FB4")
			(pinfunction "FB4")
			(pintype "input")
		)
		(pad "25" smd rect
			(at 1.624 -3.138 270)
			(size 0.3 1.125)
			(layers "F.Cu" "F.Mask" "F.Paste")
			(net 39 "/Supply/QDCDC1_VCC")
			(pinfunction "VCC")
			(pintype "input")
		)
		(pad "26" smd rect
			(at 0.972 -3.138 270)
			(size 0.3 1.125)
			(layers "F.Cu" "F.Mask" "F.Paste")
			(net 281 "/Supply/PG2")
			(pinfunction "GPIO")
			(pintype "input")
		)
		(pad "27" smd rect
			(at 0.325 -3.138 270)
			(size 0.3 1.125)
			(layers "F.Cu" "F.Mask" "F.Paste")
			(net 1 "GND")
			(pinfunction "GND")
			(pintype "passive")
		)
		(pad "28" smd rect
			(at -0.328 -3.138 270)
			(size 0.3 1.125)
			(layers "F.Cu" "F.Mask" "F.Paste")
			(net 38 "VDC")
			(pinfunction "VIN")
			(pintype "input")
		)
		(pad "29" smd rect
			(at -0.975 -3.138 270)
			(size 0.3 1.125)
			(layers "F.Cu" "F.Mask" "F.Paste")
			(net 38 "VDC")
			(pinfunction "VIN")
			(pintype "passive")
		)
		(pad "30" smd rect
			(at -1.625 -3.138 270)
			(size 0.3 1.125)
			(layers "F.Cu" "F.Mask" "F.Paste")
			(net 1 "GND")
			(pinfunction "SGND2")
			(pintype "power_out")
		)
		(pad "31" smd rect
			(at -2.275 -3.138 270)
			(size 0.3 1.125)
			(layers "F.Cu" "F.Mask" "F.Paste")
			(net 216 "/Supply/FB3")
			(pinfunction "FB3")
			(pintype "input")
		)
		(pad "32" smd rect
			(at -2.926 -3.138 270)
			(size 0.3 1.125)
			(layers "F.Cu" "F.Mask" "F.Paste")
			(net 35 "/Supply/spare_local")
			(pinfunction "VOUT3")
			(pintype "passive")
		)
		(pad "33" smd rect
			(at -0.863 -0.863 270)
			(size 1.725 1.725)
			(layers "F.Cu" "F.Mask" "F.Paste")
			(net 1 "GND")
			(pinfunction "GND")
			(pintype "passive")
			(solder_paste_margin -0.1)
		)
		(pad "33" smd rect
			(at -0.863 0.86 270)
			(size 1.725 1.725)
			(layers "F.Cu" "F.Mask" "F.Paste")
			(net 1 "GND")
			(pinfunction "GND")
			(pintype "passive")
			(solder_paste_margin -0.1)
		)
		(pad "33" smd rect
			(at 0.86 -0.863 270)
			(size 1.725 1.725)
			(layers "F.Cu" "F.Mask" "F.Paste")
			(net 1 "GND")
			(pinfunction "GND")
			(pintype "passive")
			(solder_paste_margin -0.1)
		)
		(pad "33" smd rect
			(at 0.86 0.86 270)
			(size 1.725 1.725)
			(layers "F.Cu" "F.Mask" "F.Paste")
			(net 1 "GND")
			(pinfunction "GND")
			(pintype "passive")
			(solder_paste_margin -0.1)
		)
	)
	(footprint "antmicro-footprints:R_0402_1005Metric"
		(layer "F.Cu")
		(at 93.738501 126.721921 -90)
		(descr "Resistor SMD 0402")
		(tags "resistor SMD 0402")
		(property "Reference" "R19"
			(at -1.122484 -0.772697 270)
			(layer "F.SilkS")
			(hide yes)
			(effects
				(font
					(size 0.7 0.7)
					(thickness 0.15)
				)
				(justify left bottom)
			)
		)
		(property "Value" "R_330R_0402"
			(at -1.011843 1.772047 270)
			(layer "F.Fab")
			(effects
				(font
					(size 0.7 0.7)
					(thickness 0.15)
				)
				(justify left bottom)
			)
		)
		(property "Datasheet" "https://www.bourns.com/docs/product-datasheets/cr.pdf"
			(at 0 0 270)
			(layer "F.Fab")
			(hide yes)
			(effects
				(font
					(size 1.27 1.27)
					(thickness 0.15)
				)
			)
		)
		(property "Author" "Antmicro"
			(at -32.98342 220.460422 0)
			(layer "F.Fab")
			(hide yes)
			(effects
				(font
					(size 1 1)
					(thickness 0.15)
				)
			)
		)
		(property "License" "Apache-2.0"
			(at -32.98342 220.460422 0)
			(layer "F.Fab")
			(hide yes)
			(effects
				(font
					(size 1 1)
					(thickness 0.15)
				)
			)
		)
		(property "MPN" "CR0402-FX-3300GLF"
			(at -32.98342 220.460422 0)
			(layer "F.Fab")
			(hide yes)
			(effects
				(font
					(size 1 1)
					(thickness 0.15)
				)
			)
		)
		(property "Manufacturer" "Bourns"
			(at -32.98342 220.460422 0)
			(layer "F.Fab")
			(hide yes)
			(effects
				(font
					(size 1 1)
					(thickness 0.15)
				)
			)
		)
		(property "Tolerance" "1%"
			(at -32.98342 220.460422 0)
			(layer "F.Fab")
			(hide yes)
			(effects
				(font
					(size 1 1)
					(thickness 0.15)
				)
			)
		)
		(property "Val" "330R"
			(at -32.98342 220.460422 0)
			(layer "F.Fab")
			(hide yes)
			(effects
				(font
					(size 1 1)
					(thickness 0.15)
				)
			)
		)
		(sheetname "/FPGA Config/")
		(sheetfile "fpga-config.kicad_sch")
		(attr smd)
		(fp_rect
			(start -0.93 -0.47)
			(end 0.93 0.47)
			(stroke
				(width 0.05)
				(type solid)
			)
			(fill no)
			(layer "F.CrtYd")
		)
		(fp_rect
			(start -0.5 -0.25)
			(end 0.5 0.25)
			(stroke
				(width 0.15)
				(type solid)
			)
			(fill no)
			(layer "F.Fab")
		)
		(pad "1" smd roundrect
			(at -0.485 0 270)
			(size 0.59 0.64)
			(layers "F.Cu" "F.Mask" "F.Paste")
			(roundrect_rratio 0.25)
			(net 200 "+3V3")
			(pintype "passive")
		)
		(pad "2" smd roundrect
			(at 0.485 0 270)
			(size 0.59 0.64)
			(layers "F.Cu" "F.Mask" "F.Paste")
			(roundrect_rratio 0.25)
			(net 613 "/FPGA Config/DONE")
			(pintype "passive")
		)
	)
	(footprint "antmicro-footprints:R_0402_1005Metric"
		(layer "F.Cu")
		(at 99.850501 117.691 -90)
		(descr "Resistor SMD 0402")
		(tags "resistor SMD 0402")
		(property "Reference" "R63"
			(at -1.122484 -0.772697 270)
			(layer "F.SilkS")
			(hide yes)
			(effects
				(font
					(size 0.7 0.7)
					(thickness 0.15)
				)
				(justify left bottom)
			)
		)
		(property "Value" "R_330R_0402"
			(at -1.011843 1.772047 270)
			(layer "F.Fab")
			(effects
				(font
					(size 0.7 0.7)
					(thickness 0.15)
				)
				(justify left bottom)
			)
		)
		(property "Datasheet" "https://www.bourns.com/docs/product-datasheets/cr.pdf"
			(at 0 0 270)
			(layer "F.Fab")
			(hide yes)
			(effects
				(font
					(size 1.27 1.27)
					(thickness 0.15)
				)
			)
		)
		(property "Author" "Antmicro"
			(at -17.840499 217.541501 0)
			(layer "F.Fab")
			(hide yes)
			(effects
				(font
					(size 1 1)
					(thickness 0.15)
				)
			)
		)
		(property "License" "Apache-2.0"
			(at -17.840499 217.541501 0)
			(layer "F.Fab")
			(hide yes)
			(effects
				(font
					(size 1 1)
					(thickness 0.15)
				)
			)
		)
		(property "MPN" "CR0402-FX-3300GLF"
			(at -17.840499 217.541501 0)
			(layer "F.Fab")
			(hide yes)
			(effects
				(font
					(size 1 1)
					(thickness 0.15)
				)
			)
		)
		(property "Manufacturer" "Bourns"
			(at -17.840499 217.541501 0)
			(layer "F.Fab")
			(hide yes)
			(effects
				(font
					(size 1 1)
					(thickness 0.15)
				)
			)
		)
		(property "Tolerance" "1%"
			(at -17.840499 217.541501 0)
			(layer "F.Fab")
			(hide yes)
			(effects
				(font
					(size 1 1)
					(thickness 0.15)
				)
			)
		)
		(property "Val" "330R"
			(at -17.840499 217.541501 0)
			(layer "F.Fab")
			(hide yes)
			(effects
				(font
					(size 1 1)
					(thickness 0.15)
				)
			)
		)
		(sheetname "/DDR5 SODIMM/")
		(sheetfile "ddr5-sodimm.kicad_sch")
		(attr smd)
		(fp_rect
			(start -0.93 -0.47)
			(end 0.93 0.47)
			(stroke
				(width 0.05)
				(type solid)
			)
			(fill no)
			(layer "F.CrtYd")
		)
		(fp_rect
			(start -0.5 -0.25)
			(end 0.5 0.25)
			(stroke
				(width 0.15)
				(type solid)
			)
			(fill no)
			(layer "F.Fab")
		)
		(pad "1" smd roundrect
			(at -0.485 0 270)
			(size 0.59 0.64)
			(layers "F.Cu" "F.Mask" "F.Paste")
			(roundrect_rratio 0.25)
			(net 301 "Net-(D9-C_{R})")
			(pintype "passive")
		)
		(pad "2" smd roundrect
			(at 0.485 0 270)
			(size 0.59 0.64)
			(layers "F.Cu" "F.Mask" "F.Paste")
			(roundrect_rratio 0.25)
			(net 364 "Net-(Q11-D)")
			(pintype "passive")
		)
	)
	(footprint "antmicro-footprints:R_0402_1005Metric"
		(layer "F.Cu")
		(at 99.41 133.995 180)
		(descr "Resistor SMD 0402")
		(tags "resistor SMD 0402")
		(property "Reference" "R127"
			(at 4.16 -0.405 180)
			(layer "F.SilkS")
			(effects
				(font
					(size 0.7 0.7)
					(thickness 0.15)
				)
				(justify left bottom)
			)
		)
		(property "Value" "R_0R_0402"
			(at -1.011843 1.772047 180)
			(layer "F.Fab")
			(effects
				(font
					(size 0.7 0.7)
					(thickness 0.15)
				)
				(justify left bottom)
			)
		)
		(property "Datasheet" "https://industrial.panasonic.com/cdbs/www-data/pdf/RDA0000/AOA0000C301.pdf"
			(at 0 0 180)
			(layer "F.Fab")
			(hide yes)
			(effects
				(font
					(size 1.27 1.27)
					(thickness 0.15)
				)
			)
		)
		(property "Author" "Antmicro"
			(at 198.82 267.99 0)
			(layer "F.Fab")
			(hide yes)
			(effects
				(font
					(size 1 1)
					(thickness 0.15)
				)
			)
		)
		(property "Current" "1A"
			(at 198.82 267.99 0)
			(layer "F.Fab")
			(hide yes)
			(effects
				(font
					(size 1 1)
					(thickness 0.15)
				)
			)
		)
		(property "License" "Apache-2.0"
			(at 198.82 267.99 0)
			(layer "F.Fab")
			(hide yes)
			(effects
				(font
					(size 1 1)
					(thickness 0.15)
				)
			)
		)
		(property "MPN" "ERJ2GE0R00X"
			(at 198.82 267.99 0)
			(layer "F.Fab")
			(hide yes)
			(effects
				(font
					(size 1 1)
					(thickness 0.15)
				)
			)
		)
		(property "Manufacturer" "Panasonic"
			(at 198.82 267.99 0)
			(layer "F.Fab")
			(hide yes)
			(effects
				(font
					(size 1 1)
					(thickness 0.15)
				)
			)
		)
		(property "Tolerance" ""
			(at 198.82 267.99 0)
			(layer "F.Fab")
			(hide yes)
			(effects
				(font
					(size 1 1)
					(thickness 0.15)
				)
			)
		)
		(property "Val" "0R"
			(at 198.82 267.99 0)
			(layer "F.Fab")
			(hide yes)
			(effects
				(font
					(size 1 1)
					(thickness 0.15)
				)
			)
		)
		(sheetname "/I^{2}C/")
		(sheetfile "i2c.kicad_sch")
		(attr smd)
		(fp_rect
			(start -0.93 -0.47)
			(end 0.93 0.47)
			(stroke
				(width 0.05)
				(type solid)
			)
			(fill no)
			(layer "F.CrtYd")
		)
		(fp_rect
			(start -0.5 -0.25)
			(end 0.5 0.25)
			(stroke
				(width 0.15)
				(type solid)
			)
			(fill no)
			(layer "F.Fab")
		)
		(pad "1" smd roundrect
			(at -0.485 0 180)
			(size 0.59 0.64)
			(layers "F.Cu" "F.Mask" "F.Paste")
			(roundrect_rratio 0.25)
			(net 267 "VDDSPD")
			(pintype "passive")
		)
		(pad "2" smd roundrect
			(at 0.485 0 180)
			(size 0.59 0.64)
			(layers "F.Cu" "F.Mask" "F.Paste")
			(roundrect_rratio 0.25)
			(net 188 "+1V8")
			(pintype "passive")
		)
	)
)
